(kicad_pcb
	(version 20260206)
	(generator "pcbnew")
	(generator_version "10.0")
	(general
		(thickness 1.6)
		(legacy_teardrops no)
	)
	(paper "A4")
	(title_block
		(title "timecard-production-celestica-r4006 — R4006-B0001-02_R01.brd")
		(comment 1 "Time Appliance Project (Time Card) / footprints 976-980 of 1113")
	)
	(layers
		(0 "F.Cu" signal "TOP")
		(4 "In1.Cu" signal "L02_GND1")
		(6 "In2.Cu" signal "L03_SIG1")
		(8 "In3.Cu" signal "L04_GND2")
		(10 "In4.Cu" signal "L05_VCC1")
		(12 "In5.Cu" signal "L06_VCC2")
		(14 "In6.Cu" signal "L07_GND3")
		(16 "In7.Cu" signal "L08_SIG2")
		(18 "In8.Cu" signal "L09_GND4")
		(2 "B.Cu" signal "BOTTOM")
		(9 "F.Adhes" user "F.Adhesive")
		(11 "B.Adhes" user "B.Adhesive")
		(13 "F.Paste" user "Package Geometry/Pastemask Top")
		(15 "B.Paste" user "Package Geometry/Pastemask Bottom")
		(5 "F.SilkS" user "Ref Des/Silkscreen Top")
		(7 "B.SilkS" user "Ref Des/Silkscreen Bottom")
		(1 "F.Mask" user "Board Geometry/Soldermask Top")
		(3 "B.Mask" user "Board Geometry/Soldermask Bottom")
		(17 "Dwgs.User" user "User.Drawings")
		(19 "Cmts.User" user "User.Comments")
		(21 "Eco1.User" user "User.Eco1")
		(23 "Eco2.User" user "User.Eco2")
		(25 "Edge.Cuts" user "Board Geometry/Outline")
		(27 "Margin" user)
		(31 "F.CrtYd" user "Package Geometry/Place Bound Top")
		(29 "B.CrtYd" user "Package Geometry/Place Bound Bottom")
		(35 "F.Fab" user "Ref Des/Assembly Top")
		(33 "B.Fab" user "Ref Des/Assembly Bottom")
	)
	(footprint ""
		(layer "B.Cu")
		(at 103.9622 -64.2874 90)
		(property "Reference" "R309"
			(at 3.5306 -0.11557 270)
			(unlocked yes)
			(layer "B.SilkS")
			(effects
				(font
					(size 0.7874 0.5842)
					(thickness 0.1524)
				)
				(justify mirror)
			)
		)
		(property "Value" "VAL*"
			(at -0.02032 2.13233 90)
			(unlocked yes)
			(layer "B.Fab")
			(hide yes)
			(effects
				(font
					(size 0.7874 0.5842)
					(thickness 0.1524)
				)
				(justify mirror)
			)
		)
		(property "Tolerance" "TOL*"
			(at -0.044704 3.05435 90)
			(unlocked yes)
			(layer "Cmts.User")
			(hide yes)
			(effects
				(font
					(size 0.7874 0.5842)
					(thickness 0.1524)
				)
				(justify mirror)
			)
		)
		(property "User Part Number" "PARTNUM*"
			(at -0.02032 4.024884 90)
			(unlocked yes)
			(layer "Cmts.User")
			(hide yes)
			(effects
				(font
					(size 0.7874 0.5842)
					(thickness 0.1524)
				)
				(justify mirror)
			)
		)
		(property "Device Type" "RESISTOR-G155-14701-01,4.7KOHMA"
			(at -0.008382 1.210564 90)
			(unlocked yes)
			(layer "B.Fab")
			(hide yes)
			(effects
				(font
					(size 0.7874 0.5842)
					(thickness 0.1524)
				)
				(justify mirror)
			)
		)
		(duplicate_pad_numbers_are_jumpers no)
		(fp_line
			(start 1.143 -0.5588)
			(end 1.143 0.5588)
			(stroke
				(width 0.1)
				(type default)
			)
			(layer "B.SilkS")
		)
		(fp_line
			(start -1.143 -0.5588)
			(end 1.143 -0.5588)
			(stroke
				(width 0.1)
				(type default)
			)
			(layer "B.SilkS")
		)
		(fp_line
			(start 1.143 0.5588)
			(end -1.143 0.5588)
			(stroke
				(width 0.1)
				(type default)
			)
			(layer "B.SilkS")
		)
		(fp_line
			(start -1.143 0.5588)
			(end -1.143 -0.5588)
			(stroke
				(width 0.1)
				(type default)
			)
			(layer "B.SilkS")
		)
		(fp_poly
			(pts
				(xy 1.143 0.5588) (xy -1.143 0.5588) (xy -1.143 -0.5588) (xy 1.143 -0.5588)
			)
			(stroke
				(width 0)
				(type default)
			)
			(fill no)
			(layer "B.CrtYd")
		)
		(fp_line
			(start 0.508 -0.3048)
			(end 0.508 0.3048)
			(stroke
				(width 0.1)
				(type default)
			)
			(layer "B.Fab")
		)
		(fp_line
			(start -0.508 -0.3048)
			(end 0.508 -0.3048)
			(stroke
				(width 0.1)
				(type default)
			)
			(layer "B.Fab")
		)
		(fp_line
			(start 0.508 0.3048)
			(end -0.508 0.3048)
			(stroke
				(width 0.1)
				(type default)
			)
			(layer "B.Fab")
		)
		(fp_line
			(start -0.508 0.3048)
			(end -0.508 -0.3048)
			(stroke
				(width 0.1)
				(type default)
			)
			(layer "B.Fab")
		)
		(pad "1" smd rect
			(at 0.5334 0 270)
			(size 0.7112 0.6096)
			(layers "B.Cu" "B.Mask" "B.Paste")
			(net "SG")
		)
		(pad "2" smd rect
			(at -0.5334 0 270)
			(size 0.7112 0.6096)
			(layers "B.Cu" "B.Mask" "B.Paste")
			(net "FPGA_IO_5")
		)
		(zone
			(layer "B.Cu")
			(hatch none 0.5)
			(connect_pads
				(clearance 0)
			)
			(min_thickness 0.25)
			(keepout
				(tracks not_allowed)
				(vias allowed)
				(pads allowed)
				(copperpour not_allowed)
				(footprints allowed)
			)
			(placement
				(enabled no)
				(sheetname "")
			)
			(fill
				(thermal_gap 0.5)
				(thermal_bridge_width 0.5)
				(island_removal_mode 0)
			)
			(polygon
				(pts
					(xy 104.267 -64.3636) (xy 103.6574 -64.3636) (xy 103.6574 -64.2112) (xy 104.267 -64.2112)
				)
			)
		)
		(zone
			(layer "B.Cu")
			(hatch none 0.5)
			(connect_pads
				(clearance 0)
			)
			(min_thickness 0.25)
			(keepout
				(tracks allowed)
				(vias not_allowed)
				(pads allowed)
				(copperpour not_allowed)
				(footprints allowed)
			)
			(placement
				(enabled no)
				(sheetname "")
			)
			(fill
				(thermal_gap 0.5)
				(thermal_bridge_width 0.5)
				(island_removal_mode 0)
			)
			(polygon
				(pts
					(xy 104.267 -64.3636) (xy 103.6574 -64.3636) (xy 103.6574 -64.2112) (xy 104.267 -64.2112)
				)
			)
		)
	)
	(footprint ""
		(layer "B.Cu")
		(at 109.347 -42.418 90)
		(property "Reference" "C114"
			(at -1.905 -41.56075 270)
			(unlocked yes)
			(layer "B.SilkS")
			(effects
				(font
					(size 0.635 0.4064)
					(thickness 0.1524)
				)
				(justify mirror)
			)
		)
		(property "Value" "VAL*"
			(at -0.0762 2.067306 90)
			(unlocked yes)
			(layer "B.Fab")
			(hide yes)
			(effects
				(font
					(size 0.7874 0.5842)
					(thickness 0.1524)
				)
				(justify mirror)
			)
		)
		(property "Device Type" "CAPACITOR-G105-0B104-CK,0.1UF,A"
			(at -0.0508 1.127506 90)
			(unlocked yes)
			(layer "B.Fab")
			(hide yes)
			(effects
				(font
					(size 0.7874 0.5842)
					(thickness 0.1524)
				)
				(justify mirror)
			)
		)
		(property "User Part Number" "PARTNUM*"
			(at -0.1016 4.023106 90)
			(unlocked yes)
			(layer "Cmts.User")
			(hide yes)
			(effects
				(font
					(size 0.7874 0.5842)
					(thickness 0.1524)
				)
				(justify mirror)
			)
		)
		(property "Tolerance" "TOL*"
			(at -0.0762 3.032506 90)
			(unlocked yes)
			(layer "Cmts.User")
			(hide yes)
			(effects
				(font
					(size 0.7874 0.5842)
					(thickness 0.1524)
				)
				(justify mirror)
			)
		)
		(duplicate_pad_numbers_are_jumpers no)
		(fp_line
			(start 1.143 -0.5588)
			(end 1.143 0.5588)
			(stroke
				(width 0.1)
				(type default)
			)
			(layer "B.SilkS")
		)
		(fp_line
			(start -1.143 -0.5588)
			(end 1.143 -0.5588)
			(stroke
				(width 0.1)
				(type default)
			)
			(layer "B.SilkS")
		)
		(fp_line
			(start 1.143 0.5588)
			(end -1.143 0.5588)
			(stroke
				(width 0.1)
				(type default)
			)
			(layer "B.SilkS")
		)
		(fp_line
			(start -1.143 0.5588)
			(end -1.143 -0.5588)
			(stroke
				(width 0.1)
				(type default)
			)
			(layer "B.SilkS")
		)
		(fp_rect
			(start -1.143 -0.5588)
			(end 1.143 0.5588)
			(stroke
				(width 0)
				(type default)
			)
			(fill no)
			(layer "B.CrtYd")
		)
		(fp_line
			(start 0.508 -0.3048)
			(end 0.508 0.3048)
			(stroke
				(width 0.1)
				(type default)
			)
			(layer "B.Fab")
		)
		(fp_line
			(start -0.508 -0.3048)
			(end 0.508 -0.3048)
			(stroke
				(width 0.1)
				(type default)
			)
			(layer "B.Fab")
		)
		(fp_line
			(start 0.508 0.3048)
			(end -0.508 0.3048)
			(stroke
				(width 0.1)
				(type default)
			)
			(layer "B.Fab")
		)
		(fp_line
			(start -0.508 0.3048)
			(end -0.508 -0.3048)
			(stroke
				(width 0.1)
				(type default)
			)
			(layer "B.Fab")
		)
		(pad "1" smd rect
			(at 0.5334 0 270)
			(size 0.7112 0.6096)
			(layers "B.Cu" "B.Mask" "B.Paste")
			(net "XP1R0V_FPGA_VCCINT")
		)
		(pad "2" smd rect
			(at -0.5334 0 270)
			(size 0.7112 0.6096)
			(layers "B.Cu" "B.Mask" "B.Paste")
			(net "SG")
		)
		(zone
			(layer "B.Cu")
			(hatch none 0.5)
			(connect_pads
				(clearance 0)
			)
			(min_thickness 0.25)
			(keepout
				(tracks allowed)
				(vias not_allowed)
				(pads allowed)
				(copperpour not_allowed)
				(footprints allowed)
			)
			(placement
				(enabled no)
				(sheetname "")
			)
			(fill
				(thermal_gap 0.5)
				(thermal_bridge_width 0.5)
				(island_removal_mode 0)
			)
			(polygon
				(pts
					(xy 109.0422 -42.3418) (xy 109.6518 -42.3418) (xy 109.6518 -42.4942) (xy 109.0422 -42.4942)
				)
			)
		)
	)
	(footprint ""
		(layer "B.Cu")
		(at 129.159 -98.425 90)
		(property "Reference" "C73"
			(at -2.667 0.08763 270)
			(unlocked yes)
			(layer "B.SilkS")
			(effects
				(font
					(size 0.7874 0.5842)
					(thickness 0.1524)
				)
				(justify mirror)
			)
		)
		(property "Value" "VAL*"
			(at -0.0762 2.067306 90)
			(unlocked yes)
			(layer "B.Fab")
			(hide yes)
			(effects
				(font
					(size 0.7874 0.5842)
					(thickness 0.1524)
				)
				(justify mirror)
			)
		)
		(property "Device Type" "CAPACITOR-G105-0B104-EK,0.1UF,A"
			(at -0.0508 1.127506 90)
			(unlocked yes)
			(layer "B.Fab")
			(hide yes)
			(effects
				(font
					(size 0.7874 0.5842)
					(thickness 0.1524)
				)
				(justify mirror)
			)
		)
		(property "User Part Number" "PARTNUM*"
			(at -0.1016 4.023106 90)
			(unlocked yes)
			(layer "Cmts.User")
			(hide yes)
			(effects
				(font
					(size 0.7874 0.5842)
					(thickness 0.1524)
				)
				(justify mirror)
			)
		)
		(property "Tolerance" "TOL*"
			(at -0.0762 3.032506 90)
			(unlocked yes)
			(layer "Cmts.User")
			(hide yes)
			(effects
				(font
					(size 0.7874 0.5842)
					(thickness 0.1524)
				)
				(justify mirror)
			)
		)
		(duplicate_pad_numbers_are_jumpers no)
		(fp_line
			(start 1.143 -0.5588)
			(end 1.143 0.5588)
			(stroke
				(width 0.1)
				(type default)
			)
			(layer "B.SilkS")
		)
		(fp_line
			(start -1.143 -0.5588)
			(end 1.143 -0.5588)
			(stroke
				(width 0.1)
				(type default)
			)
			(layer "B.SilkS")
		)
		(fp_line
			(start 1.143 0.5588)
			(end -1.143 0.5588)
			(stroke
				(width 0.1)
				(type default)
			)
			(layer "B.SilkS")
		)
		(fp_line
			(start -1.143 0.5588)
			(end -1.143 -0.5588)
			(stroke
				(width 0.1)
				(type default)
			)
			(layer "B.SilkS")
		)
		(fp_rect
			(start -1.143 -0.5588)
			(end 1.143 0.5588)
			(stroke
				(width 0)
				(type default)
			)
			(fill no)
			(layer "B.CrtYd")
		)
		(fp_line
			(start 0.508 -0.3048)
			(end 0.508 0.3048)
			(stroke
				(width 0.1)
				(type default)
			)
			(layer "B.Fab")
		)
		(fp_line
			(start -0.508 -0.3048)
			(end 0.508 -0.3048)
			(stroke
				(width 0.1)
				(type default)
			)
			(layer "B.Fab")
		)
		(fp_line
			(start 0.508 0.3048)
			(end -0.508 0.3048)
			(stroke
				(width 0.1)
				(type default)
			)
			(layer "B.Fab")
		)
		(fp_line
			(start -0.508 0.3048)
			(end -0.508 -0.3048)
			(stroke
				(width 0.1)
				(type default)
			)
			(layer "B.Fab")
		)
		(pad "1" smd rect
			(at 0.5334 0 270)
			(size 0.7112 0.6096)
			(layers "B.Cu" "B.Mask" "B.Paste")
			(net "XP5R0V_VCC_ANT")
		)
		(pad "2" smd rect
			(at -0.5334 0 270)
			(size 0.7112 0.6096)
			(layers "B.Cu" "B.Mask" "B.Paste")
			(net "SG")
		)
		(zone
			(layer "B.Cu")
			(hatch none 0.5)
			(connect_pads
				(clearance 0)
			)
			(min_thickness 0.25)
			(keepout
				(tracks allowed)
				(vias not_allowed)
				(pads allowed)
				(copperpour not_allowed)
				(footprints allowed)
			)
			(placement
				(enabled no)
				(sheetname "")
			)
			(fill
				(thermal_gap 0.5)
				(thermal_bridge_width 0.5)
				(island_removal_mode 0)
			)
			(polygon
				(pts
					(xy 128.8542 -98.3488) (xy 129.4638 -98.3488) (xy 129.4638 -98.5012) (xy 128.8542 -98.5012)
				)
			)
		)
	)
	(footprint ""
		(layer "B.Cu")
		(at 88.138 -59.817 90)
		(property "Reference" "R168"
			(at 2.794 0.21463 270)
			(unlocked yes)
			(layer "B.SilkS")
			(effects
				(font
					(size 0.7874 0.5842)
					(thickness 0.1524)
				)
				(justify mirror)
			)
		)
		(property "Value" "VAL*"
			(at -0.02032 2.13233 90)
			(unlocked yes)
			(layer "B.Fab")
			(hide yes)
			(effects
				(font
					(size 0.7874 0.5842)
					(thickness 0.1524)
				)
				(justify mirror)
			)
		)
		(property "Tolerance" "TOL*"
			(at -0.044704 3.05435 90)
			(unlocked yes)
			(layer "Cmts.User")
			(hide yes)
			(effects
				(font
					(size 0.7874 0.5842)
					(thickness 0.1524)
				)
				(justify mirror)
			)
		)
		(property "User Part Number" "PARTNUM*"
			(at -0.02032 4.024884 90)
			(unlocked yes)
			(layer "Cmts.User")
			(hide yes)
			(effects
				(font
					(size 0.7874 0.5842)
					(thickness 0.1524)
				)
				(justify mirror)
			)
		)
		(property "Device Type" "RESISTOR-G155-11004-01,1MOHM,1%"
			(at -0.008382 1.210564 90)
			(unlocked yes)
			(layer "B.Fab")
			(hide yes)
			(effects
				(font
					(size 0.7874 0.5842)
					(thickness 0.1524)
				)
				(justify mirror)
			)
		)
		(duplicate_pad_numbers_are_jumpers no)
		(fp_line
			(start 1.143 -0.5588)
			(end 1.143 0.5588)
			(stroke
				(width 0.1)
				(type default)
			)
			(layer "B.SilkS")
		)
		(fp_line
			(start -1.143 -0.5588)
			(end 1.143 -0.5588)
			(stroke
				(width 0.1)
				(type default)
			)
			(layer "B.SilkS")
		)
		(fp_line
			(start 1.143 0.5588)
			(end -1.143 0.5588)
			(stroke
				(width 0.1)
				(type default)
			)
			(layer "B.SilkS")
		)
		(fp_line
			(start -1.143 0.5588)
			(end -1.143 -0.5588)
			(stroke
				(width 0.1)
				(type default)
			)
			(layer "B.SilkS")
		)
		(fp_rect
			(start -1.143 -0.5588)
			(end 1.143 0.5588)
			(stroke
				(width 0)
				(type default)
			)
			(fill no)
			(layer "B.CrtYd")
		)
		(fp_line
			(start 0.508 -0.3048)
			(end 0.508 0.3048)
			(stroke
				(width 0.1)
				(type default)
			)
			(layer "B.Fab")
		)
		(fp_line
			(start -0.508 -0.3048)
			(end 0.508 -0.3048)
			(stroke
				(width 0.1)
				(type default)
			)
			(layer "B.Fab")
		)
		(fp_line
			(start 0.508 0.3048)
			(end -0.508 0.3048)
			(stroke
				(width 0.1)
				(type default)
			)
			(layer "B.Fab")
		)
		(fp_line
			(start -0.508 0.3048)
			(end -0.508 -0.3048)
			(stroke
				(width 0.1)
				(type default)
			)
			(layer "B.Fab")
		)
		(pad "1" smd rect
			(at 0.5334 0 270)
			(size 0.7112 0.6096)
			(layers "B.Cu" "B.Mask" "B.Paste")
			(net "UNNAMED_9_CAPACITOR_I17_1")
		)
		(pad "2" smd rect
			(at -0.5334 0 270)
			(size 0.7112 0.6096)
			(layers "B.Cu" "B.Mask" "B.Paste")
			(net "UNNAMED_9_BNO080LGA28_I29_XOUT3")
		)
		(zone
			(layer "B.Cu")
			(hatch none 0.5)
			(connect_pads
				(clearance 0)
			)
			(min_thickness 0.25)
			(keepout
				(tracks allowed)
				(vias not_allowed)
				(pads allowed)
				(copperpour not_allowed)
				(footprints allowed)
			)
			(placement
				(enabled no)
				(sheetname "")
			)
			(fill
				(thermal_gap 0.5)
				(thermal_bridge_width 0.5)
				(island_removal_mode 0)
			)
			(polygon
				(pts
					(xy 87.8332 -59.7408) (xy 88.4428 -59.7408) (xy 88.4428 -59.8932) (xy 87.8332 -59.8932)
				)
			)
		)
	)
	(footprint ""
		(layer "B.Cu")
		(at 95.631 -26.924 180)
		(property "Reference" "C164"
			(at 0 1.73863 0)
			(unlocked yes)
			(layer "B.SilkS")
			(effects
				(font
					(size 0.7874 0.5842)
					(thickness 0.1524)
				)
				(justify mirror)
			)
		)
		(property "Value" "VAL*"
			(at -0.0762 3.134106 180)
			(unlocked yes)
			(layer "B.Fab")
			(hide yes)
			(effects
				(font
					(size 0.7874 0.5842)
					(thickness 0.1524)
				)
				(justify mirror)
			)
		)
		(property "Device Type" "CAPACITOR-G107-0F226-CM,22UF,2A"
			(at -0.0508 2.194306 180)
			(unlocked yes)
			(layer "B.Fab")
			(hide yes)
			(effects
				(font
					(size 0.7874 0.5842)
					(thickness 0.1524)
				)
				(justify mirror)
			)
		)
		(property "User Part Number" "PARTNUM*"
			(at -0.1016 5.013706 180)
			(unlocked yes)
			(layer "Cmts.User")
			(hide yes)
			(effects
				(font
					(size 0.7874 0.5842)
					(thickness 0.1524)
				)
				(justify mirror)
			)
		)
		(property "Tolerance" "TOL*"
			(at -0.0762 4.048506 180)
			(unlocked yes)
			(layer "Cmts.User")
			(hide yes)
			(effects
				(font
					(size 0.7874 0.5842)
					(thickness 0.1524)
				)
				(justify mirror)
			)
		)
		(duplicate_pad_numbers_are_jumpers no)
		(fp_line
			(start 1.5748 0.9398)
			(end -1.5748 0.9398)
			(stroke
				(width 0.1)
				(type default)
			)
			(layer "B.SilkS")
		)
		(fp_line
			(start 1.5748 -0.9398)
			(end 1.5748 0.9398)
			(stroke
				(width 0.1)
				(type default)
			)
			(layer "B.SilkS")
		)
		(fp_line
			(start -1.5748 0.9398)
			(end -1.5748 -0.9398)
			(stroke
				(width 0.1)
				(type default)
			)
			(layer "B.SilkS")
		)
		(fp_line
			(start -1.5748 -0.9398)
			(end 1.5748 -0.9398)
			(stroke
				(width 0.1)
				(type default)
			)
			(layer "B.SilkS")
		)
		(fp_rect
			(start -1.5748 0.9398)
			(end 1.5748 -0.9398)
			(stroke
				(width 0)
				(type default)
			)
			(fill no)
			(layer "B.CrtYd")
		)
		(fp_line
			(start 1.016 0.635)
			(end -1.016 0.635)
			(stroke
				(width 0.1)
				(type default)
			)
			(layer "B.Fab")
		)
		(fp_line
			(start 1.016 -0.635)
			(end 1.016 0.635)
			(stroke
				(width 0.1)
				(type default)
			)
			(layer "B.Fab")
		)
		(fp_line
			(start -1.016 0.635)
			(end -1.016 -0.635)
			(stroke
				(width 0.1)
				(type default)
			)
			(layer "B.Fab")
		)
		(fp_line
			(start -1.016 -0.635)
			(end 1.016 -0.635)
			(stroke
				(width 0.1)
				(type default)
			)
			(layer "B.Fab")
		)
		(pad "1" smd rect
			(at 0.8382 0)
			(size 0.9652 1.3716)
			(layers "B.Cu" "B.Mask" "B.Paste")
			(net "XP2R5V_FPGA")
		)
		(pad "2" smd rect
			(at -0.8382 0)
			(size 0.9652 1.3716)
			(layers "B.Cu" "B.Mask" "B.Paste")
			(net "SG")
		)
		(zone
			(layer "B.Cu")
			(hatch none 0.5)
			(connect_pads
				(clearance 0)
			)
			(min_thickness 0.25)
			(keepout
				(tracks allowed)
				(vias not_allowed)
				(pads allowed)
				(copperpour not_allowed)
				(footprints allowed)
			)
			(placement
				(enabled no)
				(sheetname "")
			)
			(fill
				(thermal_gap 0.5)
				(thermal_bridge_width 0.5)
				(island_removal_mode 0)
			)
			(polygon
				(pts
					(xy 95.8596 -27.559) (xy 95.4024 -27.559) (xy 95.4024 -26.289) (xy 95.8596 -26.289)
				)
			)
		)
	)
)
